# S9S_MB_2U (Grand Teton) — schematic netlist excerpt (pin names and nets, part order shuffled) for the footprints in the layout excerpt that follows; sources: Cadence DE-HDL packaged netlist, KiCad conversion of 03242023_DA0F0TMBIJ0_F0T_Motherboard_J_brd_V01_OCP.brd

PC582  Q_CAPP  270UF 16V 20% OSCON  pkg THLF  page 285 : A = SW_P12V_PVCCIN_CPU1_FLT ; B = GND
PR4225  Q_RES  0 5% CHIP  pkg 0402LF  page 274 : A = NC_PVCCINFAON_CPU0_ACSP7 ; B = GND
C271  Q_CAP  22UF 4V 20% X6S  pkg C0402  page 77 : A = PVCCIN_CPU1 ; B = GND

(kicad_pcb
	(version 20260206)
	(generator "pcbnew")
	(generator_version "10.0")
	(general
		(thickness 1.6)
		(legacy_teardrops no)
	)
	(paper "A4")
	(title_block
		(title "03242023_DA0F0TMBIJ0_F0T_Motherboard_J_brd_V01_OCP.brd")
		(comment 1 "Grand Teton / footprints 2514-2516 of 6105")
	)
	(layers
		(0 "F.Cu" signal "TOP")
		(4 "In1.Cu" signal "GND")
		(6 "In2.Cu" signal "IN1")
		(8 "In3.Cu" signal "GND1")
		(10 "In4.Cu" signal "IN2")
		(12 "In5.Cu" signal "GND2")
		(14 "In6.Cu" signal "IN3")
		(16 "In7.Cu" signal "GND3")
		(18 "In8.Cu" signal "VCC")
		(20 "In9.Cu" signal "VCC1")
		(22 "In10.Cu" signal "GND4")
		(24 "In11.Cu" signal "IN4")
		(26 "In12.Cu" signal "GND5")
		(28 "In13.Cu" signal "IN5")
		(30 "In14.Cu" signal "GND6")
		(32 "In15.Cu" signal "IN6")
		(34 "In16.Cu" signal "GND7")
		(2 "B.Cu" signal "BOTTOM")
		(9 "F.Adhes" user "F.Adhesive")
		(11 "B.Adhes" user "B.Adhesive")
		(13 "F.Paste" user "Package Geometry/Pastemask Top")
		(15 "B.Paste" user "Package Geometry/Pastemask Bottom")
		(5 "F.SilkS" user "Ref Des/Silkscreen Top")
		(7 "B.SilkS" user "Ref Des/Silkscreen Bottom")
		(1 "F.Mask" user "Board Geometry/Soldermask Top")
		(3 "B.Mask" user "Board Geometry/Soldermask Bottom")
		(17 "Dwgs.User" user "User.Drawings")
		(19 "Cmts.User" user "User.Comments")
		(21 "Eco1.User" user "User.Eco1")
		(23 "Eco2.User" user "User.Eco2")
		(25 "Edge.Cuts" user "Board Geometry/Outline")
		(27 "Margin" user)
		(31 "F.CrtYd" user "Package Geometry/Place Bound Top")
		(29 "B.CrtYd" user "Package Geometry/Place Bound Bottom")
		(35 "F.Fab" user "Ref Des/Assembly Top")
		(33 "B.Fab" user "Ref Des/Assembly Bottom")
	)
	(footprint ""
		(layer "F.Cu")
		(at 106.3244 -252.956568 -90)
		(property "Reference" "C271"
			(at 0 0 270)
			(layer "F.SilkS")
			(hide yes)
			(effects
				(font
					(size 1.27 1.27)
				)
			)
		)
		(property "Value" ""
			(at 0 0 270)
			(layer "F.Fab")
			(effects
				(font
					(size 1.27 1.27)
				)
			)
		)
		(duplicate_pad_numbers_are_jumpers no)
		(fp_line
			(start -0.7874 0.4064)
			(end -0.7874 -0.4064)
			(stroke
				(width 0.1524)
				(type default)
			)
			(layer "F.SilkS")
		)
		(fp_line
			(start 0.7874 0.4064)
			(end -0.7874 0.4064)
			(stroke
				(width 0.1524)
				(type default)
			)
			(layer "F.SilkS")
		)
		(fp_line
			(start -0.7874 -0.4064)
			(end 0.7874 -0.4064)
			(stroke
				(width 0.1524)
				(type default)
			)
			(layer "F.SilkS")
		)
		(fp_line
			(start 0.7874 -0.4064)
			(end 0.7874 0.4064)
			(stroke
				(width 0.1524)
				(type default)
			)
			(layer "F.SilkS")
		)
		(fp_line
			(start -0.67945 0.3048)
			(end -0.67945 -0.305054)
			(stroke
				(width 0.1)
				(type default)
			)
			(layer "F.Fab")
		)
		(fp_line
			(start -0.12065 0.3048)
			(end -0.67945 0.3048)
			(stroke
				(width 0.1)
				(type default)
			)
			(layer "F.Fab")
		)
		(fp_line
			(start 0.120396 0.3048)
			(end 0.120396 0.2794)
			(stroke
				(width 0.1)
				(type default)
			)
			(layer "F.Fab")
		)
		(fp_line
			(start 0.67945 0.3048)
			(end 0.120396 0.3048)
			(stroke
				(width 0.1)
				(type default)
			)
			(layer "F.Fab")
		)
		(fp_line
			(start -0.12065 0.2794)
			(end -0.12065 0.3048)
			(stroke
				(width 0.1)
				(type default)
			)
			(layer "F.Fab")
		)
		(fp_line
			(start 0.120396 0.2794)
			(end -0.12065 0.2794)
			(stroke
				(width 0.1)
				(type default)
			)
			(layer "F.Fab")
		)
		(fp_line
			(start -0.12065 -0.2794)
			(end 0.12065 -0.2794)
			(stroke
				(width 0.1)
				(type default)
			)
			(layer "F.Fab")
		)
		(fp_line
			(start 0.12065 -0.2794)
			(end 0.12065 -0.3048)
			(stroke
				(width 0.1)
				(type default)
			)
			(layer "F.Fab")
		)
		(fp_line
			(start 0.12065 -0.3048)
			(end 0.67945 -0.3048)
			(stroke
				(width 0.1)
				(type default)
			)
			(layer "F.Fab")
		)
		(fp_line
			(start 0.67945 -0.3048)
			(end 0.67945 0.3048)
			(stroke
				(width 0.1)
				(type default)
			)
			(layer "F.Fab")
		)
		(fp_line
			(start -0.67945 -0.305054)
			(end -0.12065 -0.305054)
			(stroke
				(width 0.1)
				(type default)
			)
			(layer "F.Fab")
		)
		(fp_line
			(start -0.12065 -0.305054)
			(end -0.12065 -0.2794)
			(stroke
				(width 0.1)
				(type default)
			)
			(layer "F.Fab")
		)
		(pad "1" smd circle
			(at -0.40005 0 270)
			(size 0 0)
			(layers "F.Cu" "F.Mask" "F.Paste")
			(net "PVCCIN_CPU1")
		)
		(pad "2" smd circle
			(at 0.40005 0 270)
			(size 0 0)
			(layers "F.Cu" "F.Mask" "F.Paste")
			(net "GND")
		)
	)
	(footprint ""
		(layer "F.Cu")
		(at 422.66616 -143.675608 90)
		(property "Reference" "PR4225"
			(at 0 0 90)
			(layer "F.SilkS")
			(hide yes)
			(effects
				(font
					(size 1.27 1.27)
				)
			)
		)
		(property "Value" ""
			(at 0 0 90)
			(layer "F.Fab")
			(effects
				(font
					(size 1.27 1.27)
				)
			)
		)
		(duplicate_pad_numbers_are_jumpers no)
		(fp_line
			(start 0.7874 -0.4064)
			(end 0.7874 0.4064)
			(stroke
				(width 0.1524)
				(type default)
			)
			(layer "F.SilkS")
		)
		(fp_line
			(start -0.7874 -0.4064)
			(end 0.7874 -0.4064)
			(stroke
				(width 0.1524)
				(type default)
			)
			(layer "F.SilkS")
		)
		(fp_line
			(start 0.7874 0.4064)
			(end -0.7874 0.4064)
			(stroke
				(width 0.1524)
				(type default)
			)
			(layer "F.SilkS")
		)
		(fp_line
			(start -0.7874 0.4064)
			(end -0.7874 -0.4064)
			(stroke
				(width 0.1524)
				(type default)
			)
			(layer "F.SilkS")
		)
		(fp_line
			(start -0.12065 -0.305054)
			(end -0.12065 -0.2794)
			(stroke
				(width 0.1)
				(type default)
			)
			(layer "F.Fab")
		)
		(fp_line
			(start -0.67945 -0.305054)
			(end -0.12065 -0.305054)
			(stroke
				(width 0.1)
				(type default)
			)
			(layer "F.Fab")
		)
		(fp_line
			(start 0.67945 -0.3048)
			(end 0.67945 0.3048)
			(stroke
				(width 0.1)
				(type default)
			)
			(layer "F.Fab")
		)
		(fp_line
			(start 0.12065 -0.3048)
			(end 0.67945 -0.3048)
			(stroke
				(width 0.1)
				(type default)
			)
			(layer "F.Fab")
		)
		(fp_line
			(start 0.12065 -0.2794)
			(end 0.12065 -0.3048)
			(stroke
				(width 0.1)
				(type default)
			)
			(layer "F.Fab")
		)
		(fp_line
			(start -0.12065 -0.2794)
			(end 0.12065 -0.2794)
			(stroke
				(width 0.1)
				(type default)
			)
			(layer "F.Fab")
		)
		(fp_line
			(start 0.120396 0.2794)
			(end -0.12065 0.2794)
			(stroke
				(width 0.1)
				(type default)
			)
			(layer "F.Fab")
		)
		(fp_line
			(start -0.12065 0.2794)
			(end -0.12065 0.3048)
			(stroke
				(width 0.1)
				(type default)
			)
			(layer "F.Fab")
		)
		(fp_line
			(start 0.67945 0.3048)
			(end 0.120396 0.3048)
			(stroke
				(width 0.1)
				(type default)
			)
			(layer "F.Fab")
		)
		(fp_line
			(start 0.120396 0.3048)
			(end 0.120396 0.2794)
			(stroke
				(width 0.1)
				(type default)
			)
			(layer "F.Fab")
		)
		(fp_line
			(start -0.12065 0.3048)
			(end -0.67945 0.3048)
			(stroke
				(width 0.1)
				(type default)
			)
			(layer "F.Fab")
		)
		(fp_line
			(start -0.67945 0.3048)
			(end -0.67945 -0.305054)
			(stroke
				(width 0.1)
				(type default)
			)
			(layer "F.Fab")
		)
		(pad "1" smd circle
			(at -0.40005 0 90)
			(size 0 0)
			(layers "F.Cu" "F.Mask" "F.Paste")
			(net "NC_PVCCINFAON_CPU0_ACSP7")
		)
		(pad "2" smd circle
			(at 0.40005 0 90)
			(size 0 0)
			(layers "F.Cu" "F.Mask" "F.Paste")
			(net "GND")
		)
	)
	(footprint ""
		(layer "F.Cu")
		(at 112.604804 -344.029284 90)
		(property "Reference" "PC582"
			(at 0 0 90)
			(layer "F.SilkS")
			(hide yes)
			(effects
				(font
					(size 1.27 1.27)
				)
			)
		)
		(property "Value" ""
			(at 0 0 90)
			(layer "F.Fab")
			(effects
				(font
					(size 1.27 1.27)
				)
			)
		)
		(duplicate_pad_numbers_are_jumpers no)
		(fp_line
			(start -3.400044 1.249934)
			(end 3.400044 1.249934)
			(stroke
				(width 0.1524)
				(type default)
			)
			(layer "F.SilkS")
		)
		(fp_circle
			(center 0 1.249934)
			(end 0 4.649978)
			(stroke
				(width 0.1524)
				(type default)
			)
			(fill no)
			(layer "F.SilkS")
		)
		(fp_poly
			(pts
				(arc
					(start -3.400044 1.249934)
					(mid 0 4.649978)
					(end 3.400044 1.249934)
				)
			)
			(stroke
				(width 0)
				(type default)
			)
			(fill yes)
			(layer "F.SilkS")
		)
		(fp_circle
			(center 0 1.249934)
			(end 0 4.649978)
			(stroke
				(width 0.1)
				(type default)
			)
			(fill no)
			(layer "F.Fab")
		)
		(pad "1" thru_hole rect
			(at 0 0 90)
			(size 1.524 1.524)
			(drill 1.016)
			(layers "*.Cu" "*.Mask")
			(remove_unused_layers no)
			(net "SW_P12V_PVCCIN_CPU1_FLT")
			(clearance 0)
			(padstack
				(mode front_inner_back)
				(layer "Inner"
					(shape circle)
					(size 1.524 1.524)
					(clearance 0)
				)
				(layer "B.Cu"
					(shape rect)
					(size 1.524 1.524)
					(clearance 0)
				)
			)
		)
		(pad "2" thru_hole circle
			(at 0 2.500122 90)
			(size 1.524 1.524)
			(drill 1.016)
			(layers "*.Cu" "*.Mask")
			(remove_unused_layers no)
			(net "GND")
			(clearance 0)
		)
	)
)
